# T6G (Grand Teton) — schematic netlist excerpt (pin names and nets, part order shuffled) for the footprints in the layout excerpt that follows; sources: Cadence DE-HDL packaged netlist, KiCad conversion of 04192023_DAF0TMB3IC0_F0TG_MB_C_brd_V02_OCP.brd

J8068  PICOPROBE_BXA  DELTA-L 4.0 EMPTY  pkg TRIANG_LAUNCH_3PXB  page 229
  \1_p\  = DELTA_L_85_5INCH_IN4_DP
  \2_n\  = DELTA_L_85_5INCH_IN4_DN
  \3_g\  = DELTA_L_GND_1

PC6511  Q_CAP  22UF 4V 20% X6S  pkg C0805  page 360 : A = P1V8_CPU0_RT_1D ; B = GND

(kicad_pcb
	(version 20260206)
	(generator "pcbnew")
	(generator_version "10.0")
	(general
		(thickness 1.6)
		(legacy_teardrops no)
	)
	(paper "A4")
	(title_block
		(title "04192023_DAF0TMB3IC0_F0TG_MB_C_brd_V02_OCP.brd")
		(comment 1 "Grand Teton / footprints 7826-7827 of 8354")
	)
	(layers
		(0 "F.Cu" signal "TOP")
		(4 "In1.Cu" signal "GND")
		(6 "In2.Cu" signal "IN1")
		(8 "In3.Cu" signal "GND1")
		(10 "In4.Cu" signal "IN2")
		(12 "In5.Cu" signal "GND2")
		(14 "In6.Cu" signal "IN3")
		(16 "In7.Cu" signal "GND3")
		(18 "In8.Cu" signal "VCC")
		(20 "In9.Cu" signal "VCC1")
		(22 "In10.Cu" signal "GND4")
		(24 "In11.Cu" signal "IN4")
		(26 "In12.Cu" signal "GND5")
		(28 "In13.Cu" signal "IN5")
		(30 "In14.Cu" signal "GND6")
		(32 "In15.Cu" signal "IN6")
		(34 "In16.Cu" signal "GND7")
		(2 "B.Cu" signal "BOTTOM")
		(9 "F.Adhes" user "F.Adhesive")
		(11 "B.Adhes" user "B.Adhesive")
		(13 "F.Paste" user "Package Geometry/Pastemask Top")
		(15 "B.Paste" user "Package Geometry/Pastemask Bottom")
		(5 "F.SilkS" user "Ref Des/Silkscreen Top")
		(7 "B.SilkS" user "Ref Des/Silkscreen Bottom")
		(1 "F.Mask" user "Board Geometry/Soldermask Top")
		(3 "B.Mask" user "Board Geometry/Soldermask Bottom")
		(17 "Dwgs.User" user "User.Drawings")
		(19 "Cmts.User" user "User.Comments")
		(21 "Eco1.User" user "User.Eco1")
		(23 "Eco2.User" user "User.Eco2")
		(25 "Edge.Cuts" user "Board Geometry/Outline")
		(27 "Margin" user)
		(31 "F.CrtYd" user "Package Geometry/Place Bound Top")
		(29 "B.CrtYd" user "Package Geometry/Place Bound Bottom")
		(35 "F.Fab" user "Ref Des/Assembly Top")
		(33 "B.Fab" user "Ref Des/Assembly Bottom")
	)
	(footprint ""
		(layer "B.Cu")
		(at 440.78525 8.689848)
		(property "Reference" "J8068"
			(at 4.466336 1.99136 270)
			(unlocked yes)
			(layer "B.SilkS")
			(effects
				(font
					(size 0.7874 0.5842)
					(thickness 0.1524)
				)
				(justify left mirror)
			)
		)
		(property "Value" ""
			(at 0 0 0)
			(layer "B.Fab")
			(effects
				(font
					(size 1.27 1.27)
				)
				(justify mirror)
			)
		)
		(duplicate_pad_numbers_are_jumpers no)
		(fp_line
			(start -1.2192 -2.06756)
			(end -1.2192 2.06756)
			(stroke
				(width 0.1524)
				(type default)
			)
			(layer "B.SilkS")
		)
		(fp_line
			(start -1.2192 2.06756)
			(end 1.2192 2.06756)
			(stroke
				(width 0.1524)
				(type default)
			)
			(layer "B.SilkS")
		)
		(fp_line
			(start 1.2192 -2.06756)
			(end -1.2192 -2.06756)
			(stroke
				(width 0.1524)
				(type default)
			)
			(layer "B.SilkS")
		)
		(fp_line
			(start 1.2192 2.06756)
			(end 1.2192 -2.06756)
			(stroke
				(width 0.1524)
				(type default)
			)
			(layer "B.SilkS")
		)
		(pad "" np_thru_hole circle
			(at -3.4671 -1.27 270)
			(size 1.0414 1.0414)
			(drill 1.0414)
			(layers "*.Cu" "*.Mask")
			(clearance 0.381)
			(thermal_gap 0.381)
		)
		(pad "" np_thru_hole circle
			(at -3.4671 1.27 270)
			(size 1.0414 1.0414)
			(drill 1.0414)
			(layers "*.Cu" "*.Mask")
			(clearance 0.381)
			(thermal_gap 0.381)
		)
		(pad "" np_thru_hole circle
			(at 2.8829 -1.27 270)
			(size 1.0414 1.0414)
			(drill 1.0414)
			(layers "*.Cu" "*.Mask")
			(clearance 0.381)
			(thermal_gap 0.381)
		)
		(pad "" np_thru_hole circle
			(at 2.8829 1.27 270)
			(size 1.0414 1.0414)
			(drill 1.0414)
			(layers "*.Cu" "*.Mask")
			(clearance 0.381)
			(thermal_gap 0.381)
		)
		(pad "1" smd rect
			(at -0.8255 -0.249936 270)
			(size 0.3048 0.508)
			(layers "B.Cu" "B.Mask" "B.Paste")
			(net "DELTA_L_85_5INCH_IN4_DP")
		)
		(pad "2" smd rect
			(at -0.8255 0.249936 270)
			(size 0.3048 0.508)
			(layers "B.Cu" "B.Mask" "B.Paste")
			(net "DELTA_L_85_5INCH_IN4_DN")
		)
		(pad "3" smd circle
			(at 0 0 180)
			(size 0 0)
			(layers "B.Cu" "B.Mask" "B.Paste")
			(net "DELTA_L_GND_1")
		)
		(zone
			(layers "F.Cu" "B.Cu" "In1.Cu" "In2.Cu" "In3.Cu" "In4.Cu" "In5.Cu" "In6.Cu"
				"In7.Cu" "In8.Cu" "In9.Cu" "In10.Cu" "In11.Cu" "In12.Cu" "In13.Cu" "In14.Cu"
				"In15.Cu" "In16.Cu"
			)
			(hatch none 0.5)
			(connect_pads
				(clearance 0)
			)
			(min_thickness 0.25)
			(keepout
				(tracks not_allowed)
				(vias allowed)
				(pads allowed)
				(copperpour not_allowed)
				(footprints allowed)
			)
			(placement
				(enabled no)
				(sheetname "")
			)
			(fill
				(thermal_gap 0.5)
				(thermal_bridge_width 0.5)
				(island_removal_mode 0)
			)
			(polygon
				(pts
					(arc
						(start 438.24525 7.419848)
						(mid 436.39105 7.419848)
						(end 438.24525 7.419848)
					)
				)
			)
		)
		(zone
			(layers "F.Cu" "B.Cu" "In1.Cu" "In2.Cu" "In3.Cu" "In4.Cu" "In5.Cu" "In6.Cu"
				"In7.Cu" "In8.Cu" "In9.Cu" "In10.Cu" "In11.Cu" "In12.Cu" "In13.Cu" "In14.Cu"
				"In15.Cu" "In16.Cu"
			)
			(hatch none 0.5)
			(connect_pads
				(clearance 0)
			)
			(min_thickness 0.25)
			(keepout
				(tracks not_allowed)
				(vias allowed)
				(pads allowed)
				(copperpour not_allowed)
				(footprints allowed)
			)
			(placement
				(enabled no)
				(sheetname "")
			)
			(fill
				(thermal_gap 0.5)
				(thermal_bridge_width 0.5)
				(island_removal_mode 0)
			)
			(polygon
				(pts
					(arc
						(start 438.24525 9.959848)
						(mid 436.39105 9.959848)
						(end 438.24525 9.959848)
					)
				)
			)
		)
		(zone
			(layers "F.Cu" "B.Cu" "In1.Cu" "In2.Cu" "In3.Cu" "In4.Cu" "In5.Cu" "In6.Cu"
				"In7.Cu" "In8.Cu" "In9.Cu" "In10.Cu" "In11.Cu" "In12.Cu" "In13.Cu" "In14.Cu"
				"In15.Cu" "In16.Cu"
			)
			(hatch none 0.5)
			(connect_pads
				(clearance 0)
			)
			(min_thickness 0.25)
			(keepout
				(tracks not_allowed)
				(vias allowed)
				(pads allowed)
				(copperpour not_allowed)
				(footprints allowed)
			)
			(placement
				(enabled no)
				(sheetname "")
			)
			(fill
				(thermal_gap 0.5)
				(thermal_bridge_width 0.5)
				(island_removal_mode 0)
			)
			(polygon
				(pts
					(arc
						(start 444.59525 7.419848)
						(mid 442.74105 7.419848)
						(end 444.59525 7.419848)
					)
				)
			)
		)
		(zone
			(layers "F.Cu" "B.Cu" "In1.Cu" "In2.Cu" "In3.Cu" "In4.Cu" "In5.Cu" "In6.Cu"
				"In7.Cu" "In8.Cu" "In9.Cu" "In10.Cu" "In11.Cu" "In12.Cu" "In13.Cu" "In14.Cu"
				"In15.Cu" "In16.Cu"
			)
			(hatch none 0.5)
			(connect_pads
				(clearance 0)
			)
			(min_thickness 0.25)
			(keepout
				(tracks not_allowed)
				(vias allowed)
				(pads allowed)
				(copperpour not_allowed)
				(footprints allowed)
			)
			(placement
				(enabled no)
				(sheetname "")
			)
			(fill
				(thermal_gap 0.5)
				(thermal_bridge_width 0.5)
				(island_removal_mode 0)
			)
			(polygon
				(pts
					(arc
						(start 444.59525 9.959848)
						(mid 442.74105 9.959848)
						(end 444.59525 9.959848)
					)
				)
			)
		)
		(zone
			(layer "B.Cu")
			(hatch none 0.5)
			(connect_pads
				(clearance 0)
			)
			(min_thickness 0.25)
			(keepout
				(tracks not_allowed)
				(vias allowed)
				(pads allowed)
				(copperpour not_allowed)
				(footprints allowed)
			)
			(placement
				(enabled no)
				(sheetname "")
			)
			(fill
				(thermal_gap 0.5)
				(thermal_bridge_width 0.5)
				(island_removal_mode 0)
			)
			(polygon
				(pts
					(xy 439.66765 8.141208) (xy 439.66765 8.236712) (xy 440.26455 8.236712) (xy 440.26455 8.643112)
					(xy 439.66765 8.643112) (xy 439.66765 8.736584) (xy 440.26455 8.736584) (xy 440.26455 9.142984)
					(xy 439.66765 9.142984) (xy 439.66765 9.238488) (xy 440.36615 9.238488) (xy 440.36615 8.141208)
				)
			)
		)
	)
	(footprint ""
		(layer "B.Cu")
		(at 241.758978 -315.95568 -90)
		(property "Reference" "PC6511"
			(at 0 0 90)
			(layer "B.SilkS")
			(hide yes)
			(effects
				(font
					(size 1.27 1.27)
				)
				(justify mirror)
			)
		)
		(property "Value" ""
			(at 0 0 90)
			(layer "B.Fab")
			(effects
				(font
					(size 1.27 1.27)
				)
				(justify mirror)
			)
		)
		(duplicate_pad_numbers_are_jumpers no)
		(fp_line
			(start -1.524 0.762)
			(end 1.524 0.762)
			(stroke
				(width 0.1524)
				(type default)
			)
			(layer "B.SilkS")
		)
		(fp_line
			(start 1.524 0.762)
			(end 1.524 -0.762)
			(stroke
				(width 0.1524)
				(type default)
			)
			(layer "B.SilkS")
		)
		(fp_line
			(start -1.524 -0.762)
			(end -1.524 0.762)
			(stroke
				(width 0.1524)
				(type default)
			)
			(layer "B.SilkS")
		)
		(fp_line
			(start 1.524 -0.762)
			(end -1.524 -0.762)
			(stroke
				(width 0.1524)
				(type default)
			)
			(layer "B.SilkS")
		)
		(fp_line
			(start -1.1049 0.724916)
			(end -1.1049 -0.724916)
			(stroke
				(width 0.1)
				(type default)
			)
			(layer "B.Fab")
		)
		(fp_line
			(start 1.1049 0.724916)
			(end -1.1049 0.724916)
			(stroke
				(width 0.1)
				(type default)
			)
			(layer "B.Fab")
		)
		(fp_line
			(start -1.1049 -0.724916)
			(end 1.1049 -0.724916)
			(stroke
				(width 0.1)
				(type default)
			)
			(layer "B.Fab")
		)
		(fp_line
			(start 1.1049 -0.724916)
			(end 1.1049 0.724916)
			(stroke
				(width 0.1)
				(type default)
			)
			(layer "B.Fab")
		)
		(pad "1" smd rect
			(at 0.889 0 270)
			(size 1.016 1.27)
			(layers "B.Cu" "B.Mask" "B.Paste")
			(net "P1V8_CPU0_RT_1D")
		)
		(pad "2" smd rect
			(at -0.889 0 270)
			(size 1.016 1.27)
			(layers "B.Cu" "B.Mask" "B.Paste")
			(net "GND")
		)
	)
)
